# SCM (Grand Teton) — schematic netlist excerpt (pin names and nets, part order shuffled) for the footprints in the layout excerpt that follows; sources: Cadence DE-HDL packaged netlist, KiCad conversion of 12092022_DA0F0TMDCD0_F0T_Management_Board_D_brd_V3_OCP.brd

R778  Q_RES  100K 1% CHIP  pkg 0402LF  page 15 : A = P3V_BAT_SENSOR ; B = GND
R294  Q_RES  0 5% CHIP  pkg 0402LF  page 28 : A = SMB_BMC_MM15_SDA ; B = SMB_BMC_MM15_R1_SDA

(kicad_pcb
	(version 20260206)
	(generator "pcbnew")
	(generator_version "10.0")
	(general
		(thickness 1.6)
		(legacy_teardrops no)
	)
	(paper "A4")
	(title_block
		(title "12092022_DA0F0TMDCD0_F0T_Management_Board_D_brd_V3_OCP.brd")
		(comment 1 "Grand Teton / footprints 1320-1321 of 1440")
	)
	(layers
		(0 "F.Cu" signal "TOP")
		(4 "In1.Cu" signal "GND")
		(6 "In2.Cu" signal "IN1")
		(8 "In3.Cu" signal "GND1")
		(10 "In4.Cu" signal "IN2")
		(12 "In5.Cu" signal "VCC")
		(14 "In6.Cu" signal "VCC1")
		(16 "In7.Cu" signal "IN3")
		(18 "In8.Cu" signal "GND2")
		(20 "In9.Cu" signal "IN4")
		(22 "In10.Cu" signal "GND3")
		(2 "B.Cu" signal "BOTTOM")
		(9 "F.Adhes" user "F.Adhesive")
		(11 "B.Adhes" user "B.Adhesive")
		(13 "F.Paste" user "Package Geometry/Pastemask Top")
		(15 "B.Paste" user "Package Geometry/Pastemask Bottom")
		(5 "F.SilkS" user "Ref Des/Silkscreen Top")
		(7 "B.SilkS" user "Ref Des/Silkscreen Bottom")
		(1 "F.Mask" user "Board Geometry/Soldermask Top")
		(3 "B.Mask" user "Board Geometry/Soldermask Bottom")
		(17 "Dwgs.User" user "User.Drawings")
		(19 "Cmts.User" user "User.Comments")
		(21 "Eco1.User" user "User.Eco1")
		(23 "Eco2.User" user "User.Eco2")
		(25 "Edge.Cuts" user "Board Geometry/Outline")
		(27 "Margin" user)
		(31 "F.CrtYd" user "Package Geometry/Place Bound Top")
		(29 "B.CrtYd" user "Package Geometry/Place Bound Bottom")
		(35 "F.Fab" user "Ref Des/Assembly Top")
		(33 "B.Fab" user "Ref Des/Assembly Bottom")
	)
	(footprint ""
		(layer "B.Cu")
		(at 15.548864 -58.7502 -90)
		(property "Reference" "R294"
			(at 0 0 90)
			(layer "B.SilkS")
			(hide yes)
			(effects
				(font
					(size 1.27 1.27)
				)
				(justify mirror)
			)
		)
		(property "Value" ""
			(at 0 0 90)
			(layer "B.Fab")
			(effects
				(font
					(size 1.27 1.27)
				)
				(justify mirror)
			)
		)
		(duplicate_pad_numbers_are_jumpers no)
		(fp_line
			(start -0.7874 0.4064)
			(end 0.7874 0.4064)
			(stroke
				(width 0.1524)
				(type default)
			)
			(layer "B.SilkS")
		)
		(fp_line
			(start 0.7874 0.4064)
			(end 0.7874 -0.4064)
			(stroke
				(width 0.1524)
				(type default)
			)
			(layer "B.SilkS")
		)
		(fp_line
			(start -0.7874 -0.4064)
			(end -0.7874 0.4064)
			(stroke
				(width 0.1524)
				(type default)
			)
			(layer "B.SilkS")
		)
		(fp_line
			(start 0.7874 -0.4064)
			(end -0.7874 -0.4064)
			(stroke
				(width 0.1524)
				(type default)
			)
			(layer "B.SilkS")
		)
		(fp_line
			(start -0.67945 0.3048)
			(end -0.120396 0.3048)
			(stroke
				(width 0.1)
				(type default)
			)
			(layer "B.Fab")
		)
		(fp_line
			(start -0.120396 0.3048)
			(end -0.120396 0.2794)
			(stroke
				(width 0.1)
				(type default)
			)
			(layer "B.Fab")
		)
		(fp_line
			(start 0.12065 0.3048)
			(end 0.67945 0.3048)
			(stroke
				(width 0.1)
				(type default)
			)
			(layer "B.Fab")
		)
		(fp_line
			(start 0.67945 0.3048)
			(end 0.67945 -0.305054)
			(stroke
				(width 0.1)
				(type default)
			)
			(layer "B.Fab")
		)
		(fp_line
			(start -0.120396 0.2794)
			(end 0.12065 0.2794)
			(stroke
				(width 0.1)
				(type default)
			)
			(layer "B.Fab")
		)
		(fp_line
			(start 0.12065 0.2794)
			(end 0.12065 0.3048)
			(stroke
				(width 0.1)
				(type default)
			)
			(layer "B.Fab")
		)
		(fp_line
			(start -0.12065 -0.2794)
			(end -0.12065 -0.3048)
			(stroke
				(width 0.1)
				(type default)
			)
			(layer "B.Fab")
		)
		(fp_line
			(start 0.12065 -0.2794)
			(end -0.12065 -0.2794)
			(stroke
				(width 0.1)
				(type default)
			)
			(layer "B.Fab")
		)
		(fp_line
			(start -0.67945 -0.3048)
			(end -0.67945 0.3048)
			(stroke
				(width 0.1)
				(type default)
			)
			(layer "B.Fab")
		)
		(fp_line
			(start -0.12065 -0.3048)
			(end -0.67945 -0.3048)
			(stroke
				(width 0.1)
				(type default)
			)
			(layer "B.Fab")
		)
		(fp_line
			(start 0.12065 -0.305054)
			(end 0.12065 -0.2794)
			(stroke
				(width 0.1)
				(type default)
			)
			(layer "B.Fab")
		)
		(fp_line
			(start 0.67945 -0.305054)
			(end 0.12065 -0.305054)
			(stroke
				(width 0.1)
				(type default)
			)
			(layer "B.Fab")
		)
		(pad "1" smd circle
			(at 0.40005 0 90)
			(size 0 0)
			(layers "B.Cu" "B.Mask" "B.Paste")
			(net "SMB_BMC_MM15_SDA")
		)
		(pad "2" smd circle
			(at -0.40005 0 90)
			(size 0 0)
			(layers "B.Cu" "B.Mask" "B.Paste")
			(net "SMB_BMC_MM15_R1_SDA")
		)
	)
	(footprint ""
		(layer "B.Cu")
		(at 47.85487 -71.92137 180)
		(property "Reference" "R778"
			(at 0 0 0)
			(layer "B.SilkS")
			(hide yes)
			(effects
				(font
					(size 1.27 1.27)
				)
				(justify mirror)
			)
		)
		(property "Value" ""
			(at 0 0 0)
			(layer "B.Fab")
			(effects
				(font
					(size 1.27 1.27)
				)
				(justify mirror)
			)
		)
		(duplicate_pad_numbers_are_jumpers no)
		(fp_line
			(start 0.7874 0.4064)
			(end 0.7874 -0.4064)
			(stroke
				(width 0.1524)
				(type default)
			)
			(layer "B.SilkS")
		)
		(fp_line
			(start 0.7874 -0.4064)
			(end -0.7874 -0.4064)
			(stroke
				(width 0.1524)
				(type default)
			)
			(layer "B.SilkS")
		)
		(fp_line
			(start -0.7874 0.4064)
			(end 0.7874 0.4064)
			(stroke
				(width 0.1524)
				(type default)
			)
			(layer "B.SilkS")
		)
		(fp_line
			(start -0.7874 -0.4064)
			(end -0.7874 0.4064)
			(stroke
				(width 0.1524)
				(type default)
			)
			(layer "B.SilkS")
		)
		(fp_line
			(start 0.67945 0.3048)
			(end 0.67945 -0.305054)
			(stroke
				(width 0.1)
				(type default)
			)
			(layer "B.Fab")
		)
		(fp_line
			(start 0.67945 -0.305054)
			(end 0.12065 -0.305054)
			(stroke
				(width 0.1)
				(type default)
			)
			(layer "B.Fab")
		)
		(fp_line
			(start 0.12065 0.3048)
			(end 0.67945 0.3048)
			(stroke
				(width 0.1)
				(type default)
			)
			(layer "B.Fab")
		)
		(fp_line
			(start 0.12065 0.2794)
			(end 0.12065 0.3048)
			(stroke
				(width 0.1)
				(type default)
			)
			(layer "B.Fab")
		)
		(fp_line
			(start 0.12065 -0.2794)
			(end -0.12065 -0.2794)
			(stroke
				(width 0.1)
				(type default)
			)
			(layer "B.Fab")
		)
		(fp_line
			(start 0.12065 -0.305054)
			(end 0.12065 -0.2794)
			(stroke
				(width 0.1)
				(type default)
			)
			(layer "B.Fab")
		)
		(fp_line
			(start -0.120396 0.3048)
			(end -0.120396 0.2794)
			(stroke
				(width 0.1)
				(type default)
			)
			(layer "B.Fab")
		)
		(fp_line
			(start -0.120396 0.2794)
			(end 0.12065 0.2794)
			(stroke
				(width 0.1)
				(type default)
			)
			(layer "B.Fab")
		)
		(fp_line
			(start -0.12065 -0.2794)
			(end -0.12065 -0.3048)
			(stroke
				(width 0.1)
				(type default)
			)
			(layer "B.Fab")
		)
		(fp_line
			(start -0.12065 -0.3048)
			(end -0.67945 -0.3048)
			(stroke
				(width 0.1)
				(type default)
			)
			(layer "B.Fab")
		)
		(fp_line
			(start -0.67945 0.3048)
			(end -0.120396 0.3048)
			(stroke
				(width 0.1)
				(type default)
			)
			(layer "B.Fab")
		)
		(fp_line
			(start -0.67945 -0.3048)
			(end -0.67945 0.3048)
			(stroke
				(width 0.1)
				(type default)
			)
			(layer "B.Fab")
		)
		(pad "1" smd circle
			(at 0.40005 0)
			(size 0 0)
			(layers "B.Cu" "B.Mask" "B.Paste")
			(net "P3V_BAT_SENSOR")
		)
		(pad "2" smd circle
			(at -0.40005 0)
			(size 0 0)
			(layers "B.Cu" "B.Mask" "B.Paste")
			(net "GND")
		)
	)
)
